FILE_TYPE = MACRO_DRAWING;
SET COLOR_WIRE YELLOW;
SET COLOR_PROP MONO;
SET COLOR_DOT WHITE;
SET COLOR_ARC YELLOW;
SET COLOR_BODY GREEN;
SET COLOR_NOTE MONO;
SET PROP_DISPLAY VALUE;
SET PAGE_NUMBER P163;
FORCEADD PCA9517..1
(-1600 3250);
FORCEPROP 1 LAST POWER_GROUP GND=GND
J 0
(-1950 3000);
DISPLAY 0.617021 (-1950 3000);
PAINT ORANGE (-1950 3000);
FORCEPROP 1 LAST LOCATION U1B2
J 0
(-1725 3550);
DISPLAY 0.617021 (-1725 3550);
PAINT AQUA (-1725 3550);
FORCEPROP 1 LAST PART_NUMBER G77073-001
J 0
(-1950 3050);
DISPLAY 0.617021 (-1950 3050);
PAINT BLUE (-1950 3050);
FORCEPROP 1 LAST MATERIAL IC
J 0
(-1950 3525);
DISPLAY 0.617021 (-1950 3525);
PAINT SKYBLUE (-1950 3525);
FORCEPROP 2 LASTPIN (-2000 3150) $PN 5
J 2
(-2010 3160);
DISPLAY 0.617021 (-2010 3160);
PAINT ORANGE (-2010 3160);
FORCEPROP 2 LASTPIN (-2000 3300) $PN 2
J 2
(-2010 3310);
DISPLAY 0.617021 (-2010 3310);
PAINT ORANGE (-2010 3310);
FORCEPROP 2 LASTPIN (-1200 3300) $PN 7
J 0
(-1190 3310);
DISPLAY 0.617021 (-1190 3310);
PAINT ORANGE (-1190 3310);
FORCEPROP 2 LASTPIN (-2000 3250) $PN 3
J 2
(-2010 3260);
DISPLAY 0.617021 (-2010 3260);
PAINT ORANGE (-2010 3260);
FORCEPROP 2 LASTPIN (-1200 3250) $PN 6
J 0
(-1190 3260);
DISPLAY 0.617021 (-1190 3260);
PAINT ORANGE (-1190 3260);
FORCEPROP 2 LASTPIN (-2000 3400) $PN 1
J 2
(-2010 3410);
DISPLAY 0.617021 (-2010 3410);
PAINT ORANGE (-2010 3410);
FORCEPROP 2 LASTPIN (-1200 3400) $PN 8
J 0
(-1190 3410);
DISPLAY 0.617021 (-1190 3410);
PAINT ORANGE (-1190 3410);
FORCEPROP 1 LAST PACK_TYPE SM
J 0
(-1950 3625);
PAINT SKYBLUE (-1950 3625);
DISPLAY INVISIBLE (-1950 3625);
FORCEPROP 2 LAST CDS_LOCATION U1B2
J 0
(-1725 3550);
DISPLAY 0.617021 (-1725 3550);
PAINT AQUA (-1725 3550);
DISPLAY INVISIBLE (-1725 3550);
FORCEPROP 2 LAST SEC 1
J 0
(-1725 3600);
DISPLAY 0.680851 (-1725 3600);
PAINT MONO (-1725 3600);
DISPLAY INVISIBLE (-1725 3600);
FORCEPROP 2 LAST CDS_LIB mstr_digital
J 0
(-1600 3250);
PAINT MONO (-1600 3250);
DISPLAY INVISIBLE (-1600 3250);
FORCEPROP 2 LAST SEC_TYPE SM
J 0
(-1725 3600);
DISPLAY 1.021277 (-1725 3600);
PAINT ORANGE (-1725 3600);
DISPLAY INVISIBLE (-1725 3600);
FORCEPROP 1 LAST PATH I1
J 0
(-1475 3525);
PAINT GREEN (-1475 3525);
DISPLAY INVISIBLE (-1475 3525);
FORCEPROP 0 LAST ROOM SMB_PE_HP_CPU1
J 0
(-1725 3650);
DISPLAY 1.021277 (-1725 3650);
PAINT ORANGE (-1725 3650);
DISPLAY INVISIBLE (-1725 3650);
FORCEADD CAP_A..1
(-1950 3825);
FORCEPROP 1 LAST LOCATION C9M8
J 0
(-1900 3925);
DISPLAY 0.617021 (-1900 3925);
PAINT AQUA (-1900 3925);
FORCEPROP 1 LAST PART_NUMBER A36096-030
J 0
(-1900 3675);
DISPLAY 0.617021 (-1900 3675);
PAINT BLUE (-1900 3675);
FORCEPROP 1 LAST VALUE 0.1UF
J 0
(-1900 3875);
DISPLAY 0.617021 (-1900 3875);
PAINT SKYBLUE (-1900 3875);
FORCEPROP 1 LAST TOLERANCE 10%
J 0
(-1900 3775);
DISPLAY 0.617021 (-1900 3775);
PAINT SKYBLUE (-1900 3775);
FORCEPROP 1 LAST PACK_TYPE 0402V
J 0
(-1900 3625);
DISPLAY 0.617021 (-1900 3625);
PAINT SKYBLUE (-1900 3625);
FORCEPROP 1 LAST VOLTAGE 16V
J 0
(-1900 3825);
DISPLAY 0.617021 (-1900 3825);
PAINT SKYBLUE (-1900 3825);
FORCEPROP 1 LAST MATERIAL X7R
J 0
(-1900 3725);
DISPLAY 0.617021 (-1900 3725);
PAINT SKYBLUE (-1900 3725);
FORCEPROP 1 LASTPIN (-1950 3725) $PN 2
J 0
(-1940 3705);
DISPLAY 0.617021 (-1940 3705);
PAINT ORANGE (-1940 3705);
FORCEPROP 1 LASTPIN (-1950 3925) $PN 1
J 0
(-1940 3905);
DISPLAY 0.617021 (-1940 3905);
PAINT ORANGE (-1940 3905);
FORCEPROP 2 LAST CDS_LOCATION C9M8
J 0
(-1900 3925);
DISPLAY 0.617021 (-1900 3925);
PAINT AQUA (-1900 3925);
DISPLAY INVISIBLE (-1900 3925);
FORCEPROP 2 LAST CDS_LIB dev_discrete
J 0
(-1950 3825);
PAINT ORANGE (-1950 3825);
DISPLAY INVISIBLE (-1950 3825);
FORCEPROP 2 LAST SEC 1
J 0
(-1900 4025);
DISPLAY 0.680851 (-1900 4025);
PAINT MONO (-1900 4025);
DISPLAY INVISIBLE (-1900 4025);
FORCEPROP 2 LAST SEC_TYPE 0402V
J 0
(-1900 4025);
DISPLAY 1.021277 (-1900 4025);
PAINT ORANGE (-1900 4025);
DISPLAY INVISIBLE (-1900 4025);
FORCEPROP 1 LAST PATH I10
J 0
(-1900 3975);
DISPLAY 0.978723 (-1900 3975);
PAINT WHITE (-1900 3975);
DISPLAY INVISIBLE (-1900 3975);
FORCEPROP 0 LAST ROOM SMB_PE_HP_CPU1
J 0
(-1900 4025);
DISPLAY 1.021277 (-1900 4025);
PAINT ORANGE (-1900 4025);
DISPLAY INVISIBLE (-1900 4025);
FORCEADD GND..1
(-1950 3600);
FORCEPROP 3 LASTPIN (-1950 3650) SIG_NAME GND\g
J 0
(-1940 3660);
DISPLAY 0.659574 (-1940 3660);
PAINT MONO (-1940 3660);
DISPLAY INVISIBLE (-1940 3660);
FORCEPROP 1 LAST VOLTAGE 0
J 0
(-1950 3600);
PAINT SKYBLUE (-1950 3600);
DISPLAY INVISIBLE (-1950 3600);
FORCEPROP 2 LAST CDS_LIB mstr_symbols
J 0
(-1950 3600);
PAINT MONO (-1950 3600);
DISPLAY INVISIBLE (-1950 3600);
FORCEPROP 1 LAST SIZE 1B
J 0
(-1875 3550);
DISPLAY 0.872340 (-1875 3550);
PAINT GREEN (-1875 3550);
DISPLAY INVISIBLE (-1875 3550);
FORCEPROP 2 LAST BOM_COST NT_BASE_VRD
J 0
(-2250 3675);
DISPLAY 0.617021 (-2250 3675);
PAINT ORANGE (-2250 3675);
DISPLAY INVISIBLE (-2250 3675);
FORCEPROP 1 LAST BODY_TYPE PLUMBING
J 0
(-1995 3557);
DISPLAY 0.340426 (-1995 3557);
PAINT GREEN (-1995 3557);
DISPLAY INVISIBLE (-1995 3557);
FORCEPROP 1 LAST PATH I11
J 0
(-1875 3600);
DISPLAY 0.872340 (-1875 3600);
PAINT AQUA (-1875 3600);
DISPLAY INVISIBLE (-1875 3600);
FORCEPROP 2 LAST ROOM P2V5_LAN_AUX_VR
J 0
(-2250 3675);
DISPLAY 0.617021 (-2250 3675);
PAINT ORANGE (-2250 3675);
DISPLAY INVISIBLE (-2250 3675);
FORCEPROP 1 LAST HDL_POWER GND
J 0
(-1950 3750);
DISPLAY 0.872340 (-1950 3750);
PAINT GREEN (-1950 3750);
DISPLAY INVISIBLE (-1950 3750);
FORCEADD CAP_A..1
R 2
(-1275 3825);
FORCEPROP 1 LAST LOCATION C9M7
J 2
(-1325 3925);
DISPLAY 0.617021 (-1325 3925);
PAINT AQUA (-1325 3925);
FORCEPROP 1 LAST PART_NUMBER A36096-030
J 2
(-1325 3675);
DISPLAY 0.617021 (-1325 3675);
PAINT BLUE (-1325 3675);
FORCEPROP 1 LAST VALUE 0.1UF
J 2
(-1325 3875);
DISPLAY 0.617021 (-1325 3875);
PAINT SKYBLUE (-1325 3875);
FORCEPROP 1 LAST TOLERANCE 10%
J 2
(-1325 3775);
DISPLAY 0.617021 (-1325 3775);
PAINT SKYBLUE (-1325 3775);
FORCEPROP 1 LAST PACK_TYPE 0402V
J 2
(-1325 3625);
DISPLAY 0.617021 (-1325 3625);
PAINT SKYBLUE (-1325 3625);
FORCEPROP 1 LAST VOLTAGE 16V
J 2
(-1325 3825);
DISPLAY 0.617021 (-1325 3825);
PAINT SKYBLUE (-1325 3825);
FORCEPROP 1 LAST MATERIAL X7R
J 2
(-1325 3725);
DISPLAY 0.617021 (-1325 3725);
PAINT SKYBLUE (-1325 3725);
FORCEPROP 1 LASTPIN (-1275 3925) $PN 1
J 2
(-1285 3905);
DISPLAY 0.617021 (-1285 3905);
PAINT ORANGE (-1285 3905);
FORCEPROP 1 LASTPIN (-1275 3725) $PN 2
J 2
(-1285 3705);
DISPLAY 0.617021 (-1285 3705);
PAINT ORANGE (-1285 3705);
FORCEPROP 2 LAST SEC_TYPE 0402V
J 0
(-1325 4025);
DISPLAY 1.021277 (-1325 4025);
PAINT ORANGE (-1325 4025);
DISPLAY INVISIBLE (-1325 4025);
FORCEPROP 2 LAST SEC 1
J 0
(-1325 4025);
DISPLAY 0.680851 (-1325 4025);
PAINT MONO (-1325 4025);
DISPLAY INVISIBLE (-1325 4025);
FORCEPROP 2 LAST CDS_LIB dev_discrete
J 0
(-1275 3825);
PAINT ORANGE (-1275 3825);
DISPLAY INVISIBLE (-1275 3825);
FORCEPROP 2 LAST CDS_LOCATION C9M7
J 2
(-1325 3925);
DISPLAY 0.617021 (-1325 3925);
PAINT AQUA (-1325 3925);
DISPLAY INVISIBLE (-1325 3925);
FORCEPROP 1 LAST PATH I12
J 2
(-1325 3975);
DISPLAY 0.978723 (-1325 3975);
PAINT WHITE (-1325 3975);
DISPLAY INVISIBLE (-1325 3975);
FORCEPROP 0 LAST ROOM SMB_PE_HP_CPU1
J 0
(-1325 4025);
DISPLAY 1.021277 (-1325 4025);
PAINT ORANGE (-1325 4025);
DISPLAY INVISIBLE (-1325 4025);
FORCEADD GND..1
(-1275 3600);
FORCEPROP 3 LASTPIN (-1275 3650) SIG_NAME GND\g
J 0
(-1265 3660);
DISPLAY 0.659574 (-1265 3660);
PAINT MONO (-1265 3660);
DISPLAY INVISIBLE (-1265 3660);
FORCEPROP 1 LAST VOLTAGE 0
J 0
(-1275 3600);
PAINT SKYBLUE (-1275 3600);
DISPLAY INVISIBLE (-1275 3600);
FORCEPROP 2 LAST CDS_LIB mstr_symbols
J 0
(-1275 3600);
PAINT MONO (-1275 3600);
DISPLAY INVISIBLE (-1275 3600);
FORCEPROP 1 LAST SIZE 1B
J 0
(-1200 3550);
DISPLAY 0.872340 (-1200 3550);
PAINT GREEN (-1200 3550);
DISPLAY INVISIBLE (-1200 3550);
FORCEPROP 2 LAST BOM_COST NT_BASE_VRD
J 0
(-1575 3675);
DISPLAY 0.617021 (-1575 3675);
PAINT ORANGE (-1575 3675);
DISPLAY INVISIBLE (-1575 3675);
FORCEPROP 1 LAST BODY_TYPE PLUMBING
J 0
(-1320 3557);
DISPLAY 0.340426 (-1320 3557);
PAINT GREEN (-1320 3557);
DISPLAY INVISIBLE (-1320 3557);
FORCEPROP 1 LAST PATH I13
J 0
(-1200 3600);
DISPLAY 0.872340 (-1200 3600);
PAINT AQUA (-1200 3600);
DISPLAY INVISIBLE (-1200 3600);
FORCEPROP 2 LAST ROOM P2V5_LAN_AUX_VR
J 0
(-1575 3675);
DISPLAY 0.617021 (-1575 3675);
PAINT ORANGE (-1575 3675);
DISPLAY INVISIBLE (-1575 3675);
FORCEPROP 1 LAST HDL_POWER GND
J 0
(-1275 3750);
DISPLAY 0.872340 (-1275 3750);
PAINT GREEN (-1275 3750);
DISPLAY INVISIBLE (-1275 3750);
FORCEADD RES..2
R 2
(-750 3650);
FORCEPROP 1 LAST LOCATION R9M17
J 2
(-795 3775);
DISPLAY 0.617021 (-795 3775);
PAINT AQUA (-795 3775);
FORCEPROP 1 LAST PART_NUMBER G21796-001
J 2
(-790 3525);
DISPLAY 0.617021 (-790 3525);
PAINT BLUE (-790 3525);
FORCEPROP 1 LAST VALUE 2.0K
J 2
(-795 3725);
DISPLAY 0.617021 (-795 3725);
PAINT SKYBLUE (-795 3725);
FORCEPROP 1 LAST TOLERANCE 1%
J 2
(-795 3675);
DISPLAY 0.617021 (-795 3675);
PAINT SKYBLUE (-795 3675);
FORCEPROP 1 LAST PACK_TYPE 0402
J 2
(-790 3475);
DISPLAY 0.617021 (-790 3475);
PAINT SKYBLUE (-790 3475);
FORCEPROP 1 LAST MATERIAL CHIP
J 2
(-790 3575);
DISPLAY 0.617021 (-790 3575);
PAINT SKYBLUE (-790 3575);
FORCEPROP 1 LAST WATTAGE 1/16W
J 2
(-790 3625);
DISPLAY 0.617021 (-790 3625);
PAINT SKYBLUE (-790 3625);
FORCEPROP 1 LASTPIN (-750 3750) $PN 1
J 2
(-755 3712);
DISPLAY 0.617021 (-755 3712);
PAINT ORANGE (-755 3712);
FORCEPROP 1 LASTPIN (-750 3550) $PN 2
J 2
(-755 3560);
DISPLAY 0.617021 (-755 3560);
PAINT ORANGE (-755 3560);
FORCEPROP 2 LAST CDS_LOCATION R9M17
J 2
(-795 3775);
DISPLAY 0.617021 (-795 3775);
PAINT AQUA (-795 3775);
DISPLAY INVISIBLE (-795 3775);
FORCEPROP 2 LAST SEC 1
J 0
(-800 3875);
DISPLAY 0.680851 (-800 3875);
PAINT MONO (-800 3875);
DISPLAY INVISIBLE (-800 3875);
FORCEPROP 2 LAST SEC_TYPE 0402
J 0
(-800 3875);
DISPLAY 1.021277 (-800 3875);
PAINT ORANGE (-800 3875);
DISPLAY INVISIBLE (-800 3875);
FORCEPROP 2 LAST CDS_LIB mstr_discrete
J 2
(-750 3650);
PAINT MONO (-750 3650);
DISPLAY INVISIBLE (-750 3650);
FORCEPROP 1 LAST PATH I15
J 2
(-800 3825);
DISPLAY 0.978723 (-800 3825);
PAINT WHITE (-800 3825);
DISPLAY INVISIBLE (-800 3825);
FORCEPROP 0 LAST ROOM SMB_PE_HP_CPU1
J 0
(-775 3875);
DISPLAY 1.021277 (-775 3875);
PAINT ORANGE (-775 3875);
DISPLAY INVISIBLE (-775 3875);
FORCEADD RES..2
(-600 3650);
FORCEPROP 1 LAST LOCATION R9M16
J 0
(-555 3775);
DISPLAY 0.617021 (-555 3775);
PAINT AQUA (-555 3775);
FORCEPROP 1 LAST PART_NUMBER G21796-001
J 0
(-560 3525);
DISPLAY 0.617021 (-560 3525);
PAINT BLUE (-560 3525);
FORCEPROP 1 LAST VALUE 2.0K
J 0
(-555 3725);
DISPLAY 0.617021 (-555 3725);
PAINT SKYBLUE (-555 3725);
FORCEPROP 1 LAST TOLERANCE 1%
J 0
(-555 3675);
DISPLAY 0.617021 (-555 3675);
PAINT SKYBLUE (-555 3675);
FORCEPROP 1 LAST PACK_TYPE 0402
J 0
(-560 3475);
DISPLAY 0.617021 (-560 3475);
PAINT SKYBLUE (-560 3475);
FORCEPROP 1 LAST MATERIAL CHIP
J 0
(-560 3575);
DISPLAY 0.617021 (-560 3575);
PAINT SKYBLUE (-560 3575);
FORCEPROP 1 LAST WATTAGE 1/16W
J 0
(-560 3625);
DISPLAY 0.617021 (-560 3625);
PAINT SKYBLUE (-560 3625);
FORCEPROP 1 LASTPIN (-600 3750) $PN 1
J 0
(-595 3712);
DISPLAY 0.617021 (-595 3712);
PAINT ORANGE (-595 3712);
FORCEPROP 1 LASTPIN (-600 3550) $PN 2
J 0
(-595 3560);
DISPLAY 0.617021 (-595 3560);
PAINT ORANGE (-595 3560);
FORCEPROP 2 LAST CDS_LOCATION R9M16
J 0
(-555 3775);
DISPLAY 0.617021 (-555 3775);
PAINT AQUA (-555 3775);
DISPLAY INVISIBLE (-555 3775);
FORCEPROP 2 LAST SEC 1
J 0
(-550 3875);
DISPLAY 0.680851 (-550 3875);
PAINT MONO (-550 3875);
DISPLAY INVISIBLE (-550 3875);
FORCEPROP 2 LAST CDS_LIB mstr_discrete
J 0
(-600 3650);
PAINT MONO (-600 3650);
DISPLAY INVISIBLE (-600 3650);
FORCEPROP 2 LAST SEC_TYPE 0402
J 0
(-550 3875);
DISPLAY 1.021277 (-550 3875);
PAINT ORANGE (-550 3875);
DISPLAY INVISIBLE (-550 3875);
FORCEPROP 1 LAST PATH I16
J 0
(-550 3825);
DISPLAY 0.978723 (-550 3825);
PAINT WHITE (-550 3825);
DISPLAY INVISIBLE (-550 3825);
FORCEPROP 0 LAST ROOM SMB_PE_HP_CPU1
J 0
(-550 3875);
DISPLAY 1.021277 (-550 3875);
PAINT ORANGE (-550 3875);
DISPLAY INVISIBLE (-550 3875);
FORCEADD OFFPAGE..3
(950 3250);
FORCEPROP 2 LAST $XR0 182 
J 0
(1164 3250);
DISPLAY 0.638298 (1164 3250);
PAINT MONO (1164 3250);
FORCEPROP 2 LAST CDS_LIB mstr_standard
J 2
(950 3250);
PAINT MONO (950 3250);
DISPLAY INVISIBLE (950 3250);
FORCEPROP 1 LAST OFFPAGE TRUE
J 0
(1275 3125);
DISPLAY 0.872340 (1275 3125);
PAINT GREEN (1275 3125);
DISPLAY INVISIBLE (1275 3125);
FORCEPROP 1 LAST COMMENT_BODY TRUE
J 0
(900 3150);
DISPLAY 0.872340 (900 3150);
PAINT GREEN (900 3150);
DISPLAY INVISIBLE (900 3150);
FORCEPROP 2 LAST PATH I18
J 2
(900 3325);
DISPLAY 1.021277 (900 3325);
PAINT ORANGE (900 3325);
DISPLAY INVISIBLE (900 3325);
FORCEADD OFFPAGE..2
(950 3300);
FORCEPROP 2 LAST $XR0 182 
J 0
(1139 3300);
DISPLAY 0.638298 (1139 3300);
PAINT MONO (1139 3300);
FORCEPROP 2 LAST CDS_LIB mstr_standard
J 2
(950 3300);
PAINT MONO (950 3300);
DISPLAY INVISIBLE (950 3300);
FORCEPROP 1 LAST OFFPAGE TRUE
J 0
(1275 3175);
DISPLAY 0.872340 (1275 3175);
PAINT GREEN (1275 3175);
DISPLAY INVISIBLE (1275 3175);
FORCEPROP 1 LAST COMMENT_BODY TRUE
J 0
(905 3205);
DISPLAY 0.872340 (905 3205);
PAINT GREEN (905 3205);
DISPLAY INVISIBLE (905 3205);
FORCEPROP 2 LAST PATH I19
J 2
(900 3375);
DISPLAY 1.021277 (900 3375);
PAINT ORANGE (900 3375);
DISPLAY INVISIBLE (900 3375);
FORCEADD RES..1
(-3950 3300);
FORCEPROP 1 LAST LOCATION R6N8
J 0
(-3950 3375);
DISPLAY 0.617021 (-3950 3375);
PAINT AQUA (-3950 3375);
FORCEPROP 1 LAST PART_NUMBER G21796-066
J 0
(-4050 3200);
DISPLAY 0.617021 (-4050 3200);
PAINT BLUE (-4050 3200);
FORCEPROP 1 LAST VALUE 10.0
J 2
(-3625 3325);
DISPLAY 0.617021 (-3625 3325);
PAINT SKYBLUE (-3625 3325);
FORCEPROP 1 LAST TOLERANCE 1%
J 0
(-3800 3325);
DISPLAY 0.617021 (-3800 3325);
PAINT SKYBLUE (-3800 3325);
FORCEPROP 1 LAST PACK_TYPE 0402
J 0
(-3800 3250);
DISPLAY 0.617021 (-3800 3250);
PAINT SKYBLUE (-3800 3250);
FORCEPROP 1 LAST MATERIAL CHIP
J 0
(-4000 3250);
DISPLAY 0.617021 (-4000 3250);
PAINT SKYBLUE (-4000 3250);
FORCEPROP 1 LAST WATTAGE 1/16W
J 2
(-4075 3250);
DISPLAY 0.617021 (-4075 3250);
PAINT SKYBLUE (-4075 3250);
FORCEPROP 1 LASTPIN (-4050 3300) $PN 1
J 0
(-4038 3312);
DISPLAY 0.617021 (-4038 3312);
PAINT ORANGE (-4038 3312);
FORCEPROP 1 LASTPIN (-3850 3300) $PN 2
J 0
(-3888 3312);
DISPLAY 0.617021 (-3888 3312);
PAINT ORANGE (-3888 3312);
FORCEPROP 2 LAST CDS_LOCATION R6N8
J 0
(-3950 3375);
DISPLAY 0.617021 (-3950 3375);
PAINT AQUA (-3950 3375);
DISPLAY INVISIBLE (-3950 3375);
FORCEPROP 2 LAST SEC 1
J 0
(-4000 3500);
DISPLAY 0.680851 (-4000 3500);
PAINT MONO (-4000 3500);
DISPLAY INVISIBLE (-4000 3500);
FORCEPROP 2 LAST CDS_LIB mstr_discrete
J 0
(-3950 3300);
PAINT MONO (-3950 3300);
DISPLAY INVISIBLE (-3950 3300);
FORCEPROP 2 LAST SEC_TYPE 0402
J 0
(-4000 3500);
DISPLAY 1.021277 (-4000 3500);
PAINT ORANGE (-4000 3500);
DISPLAY INVISIBLE (-4000 3500);
FORCEPROP 1 LAST PATH I2
J 0
(-4000 3450);
DISPLAY 0.978723 (-4000 3450);
PAINT WHITE (-4000 3450);
DISPLAY INVISIBLE (-4000 3450);
FORCEPROP 0 LAST ROOM CPU1
J 0
(-3950 3475);
DISPLAY 1.021277 (-3950 3475);
PAINT ORANGE (-3950 3475);
DISPLAY INVISIBLE (-3950 3475);
FORCEADD RES..1
(-200 3300);
FORCEPROP 1 LAST LOCATION R9M14
J 0
(-250 3350);
DISPLAY 0.617021 (-250 3350);
PAINT AQUA (-250 3350);
FORCEPROP 1 LAST PART_NUMBER G21796-173
J 0
(-250 3400);
DISPLAY 0.617021 (-250 3400);
PAINT BLUE (-250 3400);
FORCEPROP 1 LAST VALUE 20.0
J 2
(-225 3200);
DISPLAY 0.617021 (-225 3200);
PAINT SKYBLUE (-225 3200);
FORCEPROP 1 LAST TOLERANCE 1%
J 0
(-200 3200);
DISPLAY 0.617021 (-200 3200);
PAINT SKYBLUE (-200 3200);
FORCEPROP 1 LAST PACK_TYPE 0402
J 0
(-225 3100);
DISPLAY 0.617021 (-225 3100);
PAINT SKYBLUE (-225 3100);
FORCEPROP 1 LAST MATERIAL CHIP
J 0
(-200 3150);
DISPLAY 0.617021 (-200 3150);
PAINT SKYBLUE (-200 3150);
FORCEPROP 1 LAST WATTAGE 1/16W
J 2
(-225 3150);
DISPLAY 0.617021 (-225 3150);
PAINT SKYBLUE (-225 3150);
FORCEPROP 2 LAST CDS_LOCATION R9M14
J 0
(-250 3350);
DISPLAY 0.617021 (-250 3350);
PAINT AQUA (-250 3350);
DISPLAY INVISIBLE (-250 3350);
FORCEPROP 2 LAST $SEC 1
J 0
(-250 3500);
PAINT MONO (-250 3500);
DISPLAY INVISIBLE (-250 3500);
FORCEPROP 2 LAST CDS_SEC 1
J 0
(-250 3500);
PAINT MONO (-250 3500);
DISPLAY INVISIBLE (-250 3500);
FORCEPROP 2 LAST CDS_LIB mstr_discrete
J 0
(-200 3300);
PAINT ORANGE (-200 3300);
DISPLAY INVISIBLE (-200 3300);
FORCEPROP 1 LAST PATH I20
J 0
(-250 3450);
DISPLAY 0.978723 (-250 3450);
PAINT WHITE (-250 3450);
DISPLAY INVISIBLE (-250 3450);
FORCEPROP 0 LAST ROOM SMB_PE_HP_CPU1
J 0
(-250 3500);
DISPLAY 1.021277 (-250 3500);
PAINT ORANGE (-250 3500);
DISPLAY INVISIBLE (-250 3500);
FORCEPROP 1 LASTPIN (-300 3300) $PN 1
J 0
(-288 3312);
DISPLAY 0.787234 (-288 3312);
PAINT ORANGE (-288 3312);
DISPLAY INVISIBLE (-288 3312);
FORCEPROP 1 LASTPIN (-100 3300) $PN 2
J 0
(-138 3312);
DISPLAY 0.787234 (-138 3312);
PAINT ORANGE (-138 3312);
DISPLAY INVISIBLE (-138 3312);
FORCEADD RES..1
(50 3250);
FORCEPROP 1 LAST LOCATION R9M13
J 0
(0 3300);
DISPLAY 0.617021 (0 3300);
PAINT AQUA (0 3300);
FORCEPROP 1 LAST PART_NUMBER G21796-173
J 0
(0 3350);
DISPLAY 0.617021 (0 3350);
PAINT BLUE (0 3350);
FORCEPROP 1 LAST VALUE 20.0
J 2
(25 3150);
DISPLAY 0.617021 (25 3150);
PAINT SKYBLUE (25 3150);
FORCEPROP 1 LAST TOLERANCE 1%
J 0
(50 3150);
DISPLAY 0.617021 (50 3150);
PAINT SKYBLUE (50 3150);
FORCEPROP 1 LAST PACK_TYPE 0402
J 0
(50 3050);
DISPLAY 0.617021 (50 3050);
PAINT SKYBLUE (50 3050);
FORCEPROP 1 LAST MATERIAL CHIP
J 0
(50 3100);
DISPLAY 0.617021 (50 3100);
PAINT SKYBLUE (50 3100);
FORCEPROP 1 LAST WATTAGE 1/16W
J 2
(25 3100);
DISPLAY 0.617021 (25 3100);
PAINT SKYBLUE (25 3100);
FORCEPROP 2 LAST CDS_LOCATION R9M13
J 0
(0 3300);
DISPLAY 0.617021 (0 3300);
PAINT AQUA (0 3300);
DISPLAY INVISIBLE (0 3300);
FORCEPROP 2 LAST $SEC 1
J 0
(0 3450);
PAINT MONO (0 3450);
DISPLAY INVISIBLE (0 3450);
FORCEPROP 2 LAST CDS_SEC 1
J 0
(0 3450);
PAINT MONO (0 3450);
DISPLAY INVISIBLE (0 3450);
FORCEPROP 2 LAST CDS_LIB mstr_discrete
J 0
(50 3250);
PAINT ORANGE (50 3250);
DISPLAY INVISIBLE (50 3250);
FORCEPROP 1 LAST PATH I21
J 0
(0 3400);
DISPLAY 0.978723 (0 3400);
PAINT WHITE (0 3400);
DISPLAY INVISIBLE (0 3400);
FORCEPROP 0 LAST ROOM SMB_PE_HP_CPU1
J 0
(0 3450);
DISPLAY 1.021277 (0 3450);
PAINT ORANGE (0 3450);
DISPLAY INVISIBLE (0 3450);
FORCEPROP 1 LASTPIN (-50 3250) $PN 1
J 0
(-38 3262);
DISPLAY 0.787234 (-38 3262);
PAINT ORANGE (-38 3262);
DISPLAY INVISIBLE (-38 3262);
FORCEPROP 1 LASTPIN (150 3250) $PN 2
J 0
(112 3262);
DISPLAY 0.787234 (112 3262);
PAINT ORANGE (112 3262);
DISPLAY INVISIBLE (112 3262);
FORCEADD OFFPAGE..2
(1000 2875);
FORCEPROP 2 LAST $XR0 160 
J 0
(1189 2875);
DISPLAY 0.638298 (1189 2875);
PAINT MONO (1189 2875);
FORCEPROP 2 LAST $XR1 108 
J 0
(1309 2875);
DISPLAY 0.638298 (1309 2875);
PAINT MONO (1309 2875);
FORCEPROP 0 LASTPIN (950 2875) SIG_NAME SMB_SLOTX24_BMC_STBY_LVC3_SCL
J 2
(958 2884);
DISPLAY 0.617021 (958 2884);
PAINT ORANGE (958 2884);
FORCEPROP 2 LAST CDS_LIB mstr_standard
J 0
(1000 2875);
PAINT ORANGE (1000 2875);
DISPLAY INVISIBLE (1000 2875);
FORCEPROP 1 LAST OFFPAGE TRUE
J 0
(1325 2750);
DISPLAY 0.872340 (1325 2750);
PAINT GREEN (1325 2750);
DISPLAY INVISIBLE (1325 2750);
FORCEPROP 1 LAST COMMENT_BODY TRUE
J 0
(955 2780);
DISPLAY 0.872340 (955 2780);
PAINT GREEN (955 2780);
DISPLAY INVISIBLE (955 2780);
FORCEPROP 2 LAST PATH I22
J 0
(1175 2950);
DISPLAY 1.021277 (1175 2950);
PAINT ORANGE (1175 2950);
DISPLAY INVISIBLE (1175 2950);
FORCEADD OFFPAGE..3
(1000 2825);
FORCEPROP 2 LAST $XR0 108 
J 0
(1214 2825);
DISPLAY 0.638298 (1214 2825);
PAINT MONO (1214 2825);
FORCEPROP 2 LAST $XR1 160 
J 0
(1334 2825);
DISPLAY 0.638298 (1334 2825);
PAINT MONO (1334 2825);
FORCEPROP 2 LAST CDS_LIB mstr_standard
J 0
(1000 2825);
PAINT ORANGE (1000 2825);
DISPLAY INVISIBLE (1000 2825);
FORCEPROP 1 LAST OFFPAGE TRUE
J 0
(1325 2700);
DISPLAY 0.872340 (1325 2700);
PAINT GREEN (1325 2700);
DISPLAY INVISIBLE (1325 2700);
FORCEPROP 1 LAST COMMENT_BODY TRUE
J 0
(950 2725);
DISPLAY 0.872340 (950 2725);
PAINT GREEN (950 2725);
DISPLAY INVISIBLE (950 2725);
FORCEPROP 2 LAST PATH I23
J 0
(1200 2900);
DISPLAY 1.021277 (1200 2900);
PAINT ORANGE (1200 2900);
DISPLAY INVISIBLE (1200 2900);
FORCEADD RES..1
(100 2825);
FORCEPROP 1 LAST LOCATION R9M12
J 0
(50 2875);
DISPLAY 0.617021 (50 2875);
PAINT AQUA (50 2875);
FORCEPROP 1 LAST PART_NUMBER G21796-173
J 0
(50 2925);
DISPLAY 0.617021 (50 2925);
PAINT BLUE (50 2925);
FORCEPROP 1 LAST VALUE 20.0
J 2
(75 2725);
DISPLAY 0.617021 (75 2725);
PAINT SKYBLUE (75 2725);
FORCEPROP 1 LAST TOLERANCE 1%
J 0
(100 2725);
DISPLAY 0.617021 (100 2725);
PAINT SKYBLUE (100 2725);
FORCEPROP 1 LAST PACK_TYPE 0402
J 0
(350 2675);
DISPLAY 0.617021 (350 2675);
PAINT SKYBLUE (350 2675);
FORCEPROP 1 LAST MATERIAL CHIP
J 0
(100 2675);
DISPLAY 0.617021 (100 2675);
PAINT SKYBLUE (100 2675);
FORCEPROP 1 LAST WATTAGE 1/16W
J 2
(75 2675);
DISPLAY 0.617021 (75 2675);
PAINT SKYBLUE (75 2675);
FORCEPROP 2 LAST CDS_LOCATION R9M12
J 0
(50 2875);
DISPLAY 0.617021 (50 2875);
PAINT AQUA (50 2875);
DISPLAY INVISIBLE (50 2875);
FORCEPROP 2 LAST $SEC 1
J 0
(50 3025);
PAINT MONO (50 3025);
DISPLAY INVISIBLE (50 3025);
FORCEPROP 2 LAST CDS_SEC 1
J 0
(50 3025);
PAINT MONO (50 3025);
DISPLAY INVISIBLE (50 3025);
FORCEPROP 2 LAST CDS_LIB mstr_discrete
J 0
(100 2825);
PAINT ORANGE (100 2825);
DISPLAY INVISIBLE (100 2825);
FORCEPROP 1 LAST PATH I24
J 0
(50 2975);
DISPLAY 0.978723 (50 2975);
PAINT WHITE (50 2975);
DISPLAY INVISIBLE (50 2975);
FORCEPROP 0 LAST ROOM SMB_PE_HP_CPU1
J 0
(50 3025);
DISPLAY 1.021277 (50 3025);
PAINT ORANGE (50 3025);
DISPLAY INVISIBLE (50 3025);
FORCEPROP 1 LASTPIN (0 2825) $PN 1
J 0
(12 2837);
DISPLAY 0.787234 (12 2837);
PAINT ORANGE (12 2837);
DISPLAY INVISIBLE (12 2837);
FORCEPROP 1 LASTPIN (200 2825) $PN 2
J 0
(162 2837);
DISPLAY 0.787234 (162 2837);
PAINT ORANGE (162 2837);
DISPLAY INVISIBLE (162 2837);
FORCEADD RES..1
(-150 2875);
FORCEPROP 1 LAST LOCATION R9M15
J 0
(-200 2925);
DISPLAY 0.617021 (-200 2925);
PAINT AQUA (-200 2925);
FORCEPROP 1 LAST PART_NUMBER G21796-173
J 0
(-200 2975);
DISPLAY 0.617021 (-200 2975);
PAINT BLUE (-200 2975);
FORCEPROP 1 LAST VALUE 20.0
J 2
(-175 2775);
DISPLAY 0.617021 (-175 2775);
PAINT SKYBLUE (-175 2775);
FORCEPROP 1 LAST TOLERANCE 1%
J 0
(-150 2775);
DISPLAY 0.617021 (-150 2775);
PAINT SKYBLUE (-150 2775);
FORCEPROP 1 LAST PACK_TYPE 0402
J 0
(100 2725);
DISPLAY 0.617021 (100 2725);
PAINT SKYBLUE (100 2725);
FORCEPROP 1 LAST MATERIAL CHIP
J 0
(-150 2725);
DISPLAY 0.617021 (-150 2725);
PAINT SKYBLUE (-150 2725);
FORCEPROP 1 LAST WATTAGE 1/16W
J 2
(-175 2725);
DISPLAY 0.617021 (-175 2725);
PAINT SKYBLUE (-175 2725);
FORCEPROP 2 LAST CDS_LOCATION R9M15
J 0
(-200 2925);
DISPLAY 0.617021 (-200 2925);
PAINT AQUA (-200 2925);
DISPLAY INVISIBLE (-200 2925);
FORCEPROP 2 LAST $SEC 1
J 0
(-200 3075);
PAINT MONO (-200 3075);
DISPLAY INVISIBLE (-200 3075);
FORCEPROP 2 LAST CDS_SEC 1
J 0
(-200 3075);
PAINT MONO (-200 3075);
DISPLAY INVISIBLE (-200 3075);
FORCEPROP 2 LAST CDS_LIB mstr_discrete
J 0
(-150 2875);
PAINT ORANGE (-150 2875);
DISPLAY INVISIBLE (-150 2875);
FORCEPROP 1 LAST PATH I25
J 0
(-200 3025);
DISPLAY 0.978723 (-200 3025);
PAINT WHITE (-200 3025);
DISPLAY INVISIBLE (-200 3025);
FORCEPROP 0 LAST ROOM SMB_PE_HP_CPU1
J 0
(-200 3075);
DISPLAY 1.021277 (-200 3075);
PAINT ORANGE (-200 3075);
DISPLAY INVISIBLE (-200 3075);
FORCEPROP 1 LASTPIN (-250 2875) $PN 1
J 0
(-238 2887);
DISPLAY 0.787234 (-238 2887);
PAINT ORANGE (-238 2887);
DISPLAY INVISIBLE (-238 2887);
FORCEPROP 1 LASTPIN (-50 2875) $PN 2
J 0
(-88 2887);
DISPLAY 0.787234 (-88 2887);
PAINT ORANGE (-88 2887);
DISPLAY INVISIBLE (-88 2887);
FORCEADD P3V3_STBY..1
(-1200 4150);
FORCEPROP 3 LASTPIN (-1200 4100) SIG_NAME P3V3_STBY\g
J 0
(-1190 4110);
DISPLAY 0.659574 (-1190 4110);
PAINT MONO (-1190 4110);
DISPLAY INVISIBLE (-1190 4110);
FORCEPROP 1 LAST VOLTAGE 3.3V
J 0
(-1245 4107);
DISPLAY 0.340426 (-1245 4107);
PAINT SKYBLUE (-1245 4107);
DISPLAY INVISIBLE (-1245 4107);
FORCEPROP 2 LAST CDS_LIB mstr_symbols
J 0
(-1200 4150);
PAINT ORANGE (-1200 4150);
DISPLAY INVISIBLE (-1200 4150);
FORCEPROP 1 LAST SIZE 1B
J 0
(-1155 4172);
DISPLAY 0.340426 (-1155 4172);
PAINT GREEN (-1155 4172);
DISPLAY INVISIBLE (-1155 4172);
FORCEPROP 1 LAST BODY_TYPE PLUMBING
J 0
(-1245 4107);
DISPLAY 0.340426 (-1245 4107);
PAINT GREEN (-1245 4107);
DISPLAY INVISIBLE (-1245 4107);
FORCEPROP 1 LAST PATH I26
J 0
(-1155 4152);
DISPLAY 0.340426 (-1155 4152);
PAINT GREEN (-1155 4152);
DISPLAY INVISIBLE (-1155 4152);
FORCEPROP 1 LAST HDL_POWER P3V3_STBY
J 0
(-1500 4025);
DISPLAY 0.872340 (-1500 4025);
PAINT ORANGE (-1500 4025);
DISPLAY INVISIBLE (-1500 4025);
FORCEADD P3V3_STBY..1
(-675 4050);
FORCEPROP 3 LASTPIN (-675 4000) SIG_NAME P3V3_STBY\g
J 0
(-665 4010);
DISPLAY 0.659574 (-665 4010);
PAINT MONO (-665 4010);
DISPLAY INVISIBLE (-665 4010);
FORCEPROP 1 LAST VOLTAGE 3.3V
J 0
(-720 4007);
DISPLAY 0.340426 (-720 4007);
PAINT SKYBLUE (-720 4007);
DISPLAY INVISIBLE (-720 4007);
FORCEPROP 1 LAST SIZE 1B
J 0
(-630 4072);
DISPLAY 0.340426 (-630 4072);
PAINT GREEN (-630 4072);
DISPLAY INVISIBLE (-630 4072);
FORCEPROP 2 LAST CDS_LIB mstr_symbols
J 0
(-675 4050);
PAINT ORANGE (-675 4050);
DISPLAY INVISIBLE (-675 4050);
FORCEPROP 1 LAST BODY_TYPE PLUMBING
J 0
(-720 4007);
DISPLAY 0.340426 (-720 4007);
PAINT GREEN (-720 4007);
DISPLAY INVISIBLE (-720 4007);
FORCEPROP 1 LAST PATH I27
J 0
(-630 4052);
DISPLAY 0.340426 (-630 4052);
PAINT GREEN (-630 4052);
DISPLAY INVISIBLE (-630 4052);
FORCEPROP 1 LAST HDL_POWER P3V3_STBY
J 0
(-975 3925);
DISPLAY 0.872340 (-975 3925);
PAINT ORANGE (-975 3925);
DISPLAY INVISIBLE (-975 3925);
FORCEADD RES..1
(-3425 3250);
FORCEPROP 1 LAST LOCATION R6N9
J 0
(-3425 3350);
DISPLAY 0.617021 (-3425 3350);
PAINT AQUA (-3425 3350);
FORCEPROP 1 LAST PART_NUMBER G21796-066
J 0
(-3575 3150);
DISPLAY 0.617021 (-3575 3150);
PAINT BLUE (-3575 3150);
FORCEPROP 1 LAST VALUE 10.0
J 2
(-3100 3275);
DISPLAY 0.617021 (-3100 3275);
PAINT SKYBLUE (-3100 3275);
FORCEPROP 1 LAST TOLERANCE 1%
J 0
(-3275 3275);
DISPLAY 0.617021 (-3275 3275);
PAINT SKYBLUE (-3275 3275);
FORCEPROP 1 LAST PACK_TYPE 0402
J 0
(-3275 3200);
DISPLAY 0.617021 (-3275 3200);
PAINT SKYBLUE (-3275 3200);
FORCEPROP 1 LAST MATERIAL CHIP
J 0
(-3475 3200);
DISPLAY 0.617021 (-3475 3200);
PAINT SKYBLUE (-3475 3200);
FORCEPROP 1 LAST WATTAGE 1/16W
J 2
(-3550 3200);
DISPLAY 0.617021 (-3550 3200);
PAINT SKYBLUE (-3550 3200);
FORCEPROP 1 LASTPIN (-3525 3250) $PN 1
J 0
(-3513 3262);
DISPLAY 0.617021 (-3513 3262);
PAINT ORANGE (-3513 3262);
FORCEPROP 1 LASTPIN (-3325 3250) $PN 2
J 0
(-3363 3262);
DISPLAY 0.617021 (-3363 3262);
PAINT ORANGE (-3363 3262);
FORCEPROP 2 LAST CDS_LOCATION R6N9
J 0
(-3425 3350);
DISPLAY 0.617021 (-3425 3350);
PAINT AQUA (-3425 3350);
DISPLAY INVISIBLE (-3425 3350);
FORCEPROP 2 LAST SEC 1
J 0
(-3475 3450);
DISPLAY 0.680851 (-3475 3450);
PAINT MONO (-3475 3450);
DISPLAY INVISIBLE (-3475 3450);
FORCEPROP 2 LAST CDS_LIB mstr_discrete
J 0
(-3425 3250);
PAINT MONO (-3425 3250);
DISPLAY INVISIBLE (-3425 3250);
FORCEPROP 2 LAST SEC_TYPE 0402
J 0
(-3475 3450);
DISPLAY 1.021277 (-3475 3450);
PAINT ORANGE (-3475 3450);
DISPLAY INVISIBLE (-3475 3450);
FORCEPROP 1 LAST PATH I3
J 0
(-3475 3400);
DISPLAY 0.978723 (-3475 3400);
PAINT WHITE (-3475 3400);
DISPLAY INVISIBLE (-3475 3400);
FORCEPROP 0 LAST ROOM CPU1
J 0
(-3425 3450);
DISPLAY 1.021277 (-3425 3450);
PAINT ORANGE (-3425 3450);
DISPLAY INVISIBLE (-3425 3450);
FORCEADD OFFPAGE..1
(-4825 3300);
FORCEPROP 2 LAST $XR0 55 
J 0
(-5076 3300);
DISPLAY 0.638298 (-5076 3300);
PAINT MONO (-5076 3300);
FORCEPROP 2 LAST CDS_LIB mstr_standard
J 0
(-4825 3300);
PAINT MONO (-4825 3300);
DISPLAY INVISIBLE (-4825 3300);
FORCEPROP 1 LAST OFFPAGE TRUE
J 0
(-4500 3175);
DISPLAY 0.872340 (-4500 3175);
PAINT GREEN (-4500 3175);
DISPLAY INVISIBLE (-4500 3175);
FORCEPROP 1 LAST COMMENT_BODY TRUE
J 0
(-4700 3200);
DISPLAY 0.872340 (-4700 3200);
PAINT GREEN (-4700 3200);
DISPLAY INVISIBLE (-4700 3200);
FORCEPROP 2 LAST PATH I4
J 0
(-4775 3375);
DISPLAY 1.021277 (-4775 3375);
PAINT ORANGE (-4775 3375);
DISPLAY INVISIBLE (-4775 3375);
FORCEADD OFFPAGE..3
R 2
(-4825 3250);
FORCEPROP 2 LAST $XR0 55 
J 0
(-5074 3250);
DISPLAY 0.638298 (-5074 3250);
PAINT MONO (-5074 3250);
FORCEPROP 2 LAST CDS_LIB mstr_standard
J 2
(-4825 3250);
PAINT MONO (-4825 3250);
DISPLAY INVISIBLE (-4825 3250);
FORCEPROP 1 LAST OFFPAGE TRUE
J 2
(-5150 3125);
DISPLAY 0.872340 (-5150 3125);
PAINT GREEN (-5150 3125);
DISPLAY INVISIBLE (-5150 3125);
FORCEPROP 1 LAST COMMENT_BODY TRUE
J 2
(-4775 3150);
DISPLAY 0.872340 (-4775 3150);
PAINT GREEN (-4775 3150);
DISPLAY INVISIBLE (-4775 3150);
FORCEPROP 2 LAST PATH I5
J 2
(-4875 3325);
DISPLAY 1.021277 (-4875 3325);
PAINT ORANGE (-4875 3325);
DISPLAY INVISIBLE (-4875 3325);
FORCEADD RES..2
(-2350 3650);
FORCEPROP 1 LAST LOCATION R9M18
J 0
(-2305 3775);
DISPLAY 0.617021 (-2305 3775);
PAINT AQUA (-2305 3775);
FORCEPROP 1 LAST PART_NUMBER G21796-294
J 0
(-2310 3525);
DISPLAY 0.617021 (-2310 3525);
PAINT BLUE (-2310 3525);
FORCEPROP 1 LAST VALUE 240
J 0
(-2305 3725);
DISPLAY 0.617021 (-2305 3725);
PAINT SKYBLUE (-2305 3725);
FORCEPROP 1 LAST TOLERANCE 1.0%
J 0
(-2305 3675);
DISPLAY 0.617021 (-2305 3675);
PAINT SKYBLUE (-2305 3675);
FORCEPROP 1 LAST PACK_TYPE 0402
J 0
(-2310 3475);
DISPLAY 0.617021 (-2310 3475);
PAINT SKYBLUE (-2310 3475);
FORCEPROP 1 LAST MATERIAL CHIP
J 0
(-2310 3575);
DISPLAY 0.617021 (-2310 3575);
PAINT SKYBLUE (-2310 3575);
FORCEPROP 1 LAST WATTAGE 1/16W
J 0
(-2310 3625);
DISPLAY 0.617021 (-2310 3625);
PAINT SKYBLUE (-2310 3625);
FORCEPROP 1 LASTPIN (-2350 3750) $PN 1
J 0
(-2345 3712);
DISPLAY 0.617021 (-2345 3712);
PAINT ORANGE (-2345 3712);
FORCEPROP 1 LASTPIN (-2350 3550) $PN 2
J 0
(-2345 3560);
DISPLAY 0.617021 (-2345 3560);
PAINT ORANGE (-2345 3560);
FORCEPROP 2 LAST CDS_LOCATION R9M18
J 0
(-2305 3775);
DISPLAY 0.617021 (-2305 3775);
PAINT AQUA (-2305 3775);
DISPLAY INVISIBLE (-2305 3775);
FORCEPROP 2 LAST SEC 1
J 0
(-2300 3875);
DISPLAY 0.680851 (-2300 3875);
PAINT MONO (-2300 3875);
DISPLAY INVISIBLE (-2300 3875);
FORCEPROP 2 LAST CDS_LIB mstr_discrete
J 0
(-2350 3650);
PAINT MONO (-2350 3650);
DISPLAY INVISIBLE (-2350 3650);
FORCEPROP 2 LAST SEC_TYPE 0402
J 0
(-2300 3875);
DISPLAY 1.021277 (-2300 3875);
PAINT ORANGE (-2300 3875);
DISPLAY INVISIBLE (-2300 3875);
FORCEPROP 1 LAST PATH I6
J 0
(-2300 3825);
DISPLAY 0.978723 (-2300 3825);
PAINT WHITE (-2300 3825);
DISPLAY INVISIBLE (-2300 3825);
FORCEPROP 0 LAST ROOM SMB_PE_HP_CPU1
J 0
(-2300 3875);
DISPLAY 1.021277 (-2300 3875);
PAINT ORANGE (-2300 3875);
DISPLAY INVISIBLE (-2300 3875);
FORCEADD RES..2
R 2
(-2475 3650);
FORCEPROP 1 LAST LOCATION R9M19
J 2
(-2520 3775);
DISPLAY 0.617021 (-2520 3775);
PAINT AQUA (-2520 3775);
FORCEPROP 1 LAST PART_NUMBER G21796-294
J 2
(-2515 3525);
DISPLAY 0.617021 (-2515 3525);
PAINT BLUE (-2515 3525);
FORCEPROP 1 LAST VALUE 240
J 2
(-2520 3725);
DISPLAY 0.617021 (-2520 3725);
PAINT SKYBLUE (-2520 3725);
FORCEPROP 1 LAST TOLERANCE 1.0%
J 2
(-2520 3675);
DISPLAY 0.617021 (-2520 3675);
PAINT SKYBLUE (-2520 3675);
FORCEPROP 1 LAST PACK_TYPE 0402
J 2
(-2515 3475);
DISPLAY 0.617021 (-2515 3475);
PAINT SKYBLUE (-2515 3475);
FORCEPROP 1 LAST MATERIAL CHIP
J 2
(-2515 3575);
DISPLAY 0.617021 (-2515 3575);
PAINT SKYBLUE (-2515 3575);
FORCEPROP 1 LAST WATTAGE 1/16W
J 2
(-2515 3625);
DISPLAY 0.617021 (-2515 3625);
PAINT SKYBLUE (-2515 3625);
FORCEPROP 1 LASTPIN (-2475 3750) $PN 1
J 2
(-2480 3712);
DISPLAY 0.617021 (-2480 3712);
PAINT ORANGE (-2480 3712);
FORCEPROP 1 LASTPIN (-2475 3550) $PN 2
J 2
(-2480 3560);
DISPLAY 0.617021 (-2480 3560);
PAINT ORANGE (-2480 3560);
FORCEPROP 2 LAST CDS_LOCATION R9M19
J 2
(-2520 3775);
DISPLAY 0.617021 (-2520 3775);
PAINT AQUA (-2520 3775);
DISPLAY INVISIBLE (-2520 3775);
FORCEPROP 2 LAST SEC 1
J 0
(-2525 3875);
DISPLAY 0.680851 (-2525 3875);
PAINT MONO (-2525 3875);
DISPLAY INVISIBLE (-2525 3875);
FORCEPROP 2 LAST CDS_LIB mstr_discrete
J 2
(-2475 3650);
PAINT MONO (-2475 3650);
DISPLAY INVISIBLE (-2475 3650);
FORCEPROP 2 LAST SEC_TYPE 0402
J 0
(-2525 3875);
DISPLAY 1.021277 (-2525 3875);
PAINT ORANGE (-2525 3875);
DISPLAY INVISIBLE (-2525 3875);
FORCEPROP 1 LAST PATH I7
J 2
(-2525 3825);
DISPLAY 0.978723 (-2525 3825);
PAINT WHITE (-2525 3825);
DISPLAY INVISIBLE (-2525 3825);
FORCEPROP 0 LAST ROOM SMB_PE_HP_CPU1
J 0
(-2500 3875);
DISPLAY 1.021277 (-2500 3875);
PAINT ORANGE (-2500 3875);
DISPLAY INVISIBLE (-2500 3875);
FORCEADD PVCCIO_CPU1..1
(-2400 4000);
FORCEPROP 3 LASTPIN (-2400 3950) SIG_NAME PVCCIO_CPU1\g
J 0
(-2390 3960);
DISPLAY 0.659574 (-2390 3960);
PAINT MONO (-2390 3960);
DISPLAY INVISIBLE (-2390 3960);
FORCEPROP 1 LAST VOLTAGE 1.1V
J 0
(-2445 3957);
DISPLAY 0.340426 (-2445 3957);
PAINT SKYBLUE (-2445 3957);
DISPLAY INVISIBLE (-2445 3957);
FORCEPROP 2 LAST CDS_LIB mstr_symbols
J 0
(-2400 4000);
PAINT ORANGE (-2400 4000);
DISPLAY INVISIBLE (-2400 4000);
FORCEPROP 1 LAST BODY_TYPE PLUMBING
J 0
(-2445 3957);
DISPLAY 0.340426 (-2445 3957);
PAINT GREEN (-2445 3957);
DISPLAY INVISIBLE (-2445 3957);
FORCEPROP 1 LAST PATH I8
J 0
(-2350 4025);
DISPLAY 0.872340 (-2350 4025);
PAINT AQUA (-2350 4025);
DISPLAY INVISIBLE (-2350 4025);
FORCEPROP 1 LAST HDL_POWER PVCCIO_CPU1
J 1
(-2400 4050);
DISPLAY 0.872340 (-2400 4050);
PAINT GREEN (-2400 4050);
DISPLAY INVISIBLE (-2400 4050);
FORCEADD PVCCIO_CPU1..1
(-2025 4150);
FORCEPROP 3 LASTPIN (-2025 4100) SIG_NAME PVCCIO_CPU1\g
J 0
(-2015 4110);
DISPLAY 0.659574 (-2015 4110);
PAINT MONO (-2015 4110);
DISPLAY INVISIBLE (-2015 4110);
FORCEPROP 1 LAST VOLTAGE 1.1V
J 0
(-2070 4107);
DISPLAY 0.340426 (-2070 4107);
PAINT SKYBLUE (-2070 4107);
DISPLAY INVISIBLE (-2070 4107);
FORCEPROP 2 LAST CDS_LIB mstr_symbols
J 0
(-2025 4150);
PAINT ORANGE (-2025 4150);
DISPLAY INVISIBLE (-2025 4150);
FORCEPROP 1 LAST BODY_TYPE PLUMBING
J 0
(-2070 4107);
DISPLAY 0.340426 (-2070 4107);
PAINT GREEN (-2070 4107);
DISPLAY INVISIBLE (-2070 4107);
FORCEPROP 1 LAST PATH I9
J 0
(-1975 4175);
DISPLAY 0.872340 (-1975 4175);
PAINT AQUA (-1975 4175);
DISPLAY INVISIBLE (-1975 4175);
FORCEPROP 1 LAST HDL_POWER PVCCIO_CPU1
J 1
(-2025 4200);
DISPLAY 0.872340 (-2025 4200);
PAINT GREEN (-2025 4200);
DISPLAY INVISIBLE (-2025 4200);
FORCEADD CAD_NOTE..1
(-1725 4550);
FORCEPROP 2 LAST CDS_LIB mstr_symbols
J 0
(-1725 4550);
PAINT MONO (-1725 4550);
DISPLAY INVISIBLE (-1725 4550);
FORCEPROP 1 LAST COMMENT_BODY TRUE
J 0
(-1700 4650);
DISPLAY 1.319149 (-1700 4650);
PAINT WHITE (-1700 4650);
DISPLAY INVISIBLE (-1700 4650);
FORCEADD DESIGN_NOTE..1
(-1725 2675);
FORCEPROP 2 LAST CDS_LIB mstr_symbols
J 0
(-1725 2675);
PAINT ORANGE (-1725 2675);
DISPLAY INVISIBLE (-1725 2675);
FORCEPROP 1 LAST COMMENT_BODY TRUE
J 0
(-1700 2775);
DISPLAY 0.978723 (-1700 2775);
PAINT ORANGE (-1700 2775);
DISPLAY INVISIBLE (-1700 2775);
FORCEADD CAD_NOTE..1
(-3975 3075);
FORCEPROP 2 LAST CDS_LIB mstr_symbols
J 0
(-3975 3075);
PAINT MONO (-3975 3075);
DISPLAY INVISIBLE (-3975 3075);
FORCEPROP 1 LAST COMMENT_BODY TRUE
J 0
(-3950 3175);
DISPLAY 1.319149 (-3950 3175);
PAINT WHITE (-3950 3175);
DISPLAY INVISIBLE (-3950 3175);
FORCEADD INTEL_CORP_BPAGE..1
(2650 500);
FORCEPROP 1 LAST CDS_CON_LAST_MODIFIED Tue Dec 01 11:52:10 2015
J 0
(1225 825);
PAINT ORANGE (1225 825);
DISPLAY INVISIBLE (1225 825);
FORCEPROP 1 LAST CUSTOM_TXT_CDS <CURRENT_DESIGN_SHEET> OF <TOTAL_DESIGN_SHEETS>
J 0
(2150 525);
PAINT GREEN (2150 525);
FORCEPROP 1 LAST CUSTOM_TXT_CDS <CON_LAST_MODIFIED>
J 0
(725 850);
PAINT GREEN (725 850);
FORCEPROP 2 LAST CUSTOM_TXT_CDS <XR_PAGE_TITLE>
J 0
(-5240 5750);
DISPLAY 0.638298 (-5240 5750);
PAINT PINK (-5240 5750);
DISPLAY INVISIBLE (-5240 5750);
FORCEPROP 1 LAST SCH_ADDRESS3 Santa Clara, CA 95052-8119
J 0
(-1325 525);
DISPLAY 0.617021 (-1325 525);
PAINT GREEN (-1325 525);
FORCEPROP 1 LAST SCH_ADDRESS2 P.O. BOX 58119
J 0
(-1325 575);
DISPLAY 0.617021 (-1325 575);
PAINT GREEN (-1325 575);
FORCEPROP 1 LAST SCH_ADDRESS1 2200 Mission College Blvd.
J 0
(-1325 625);
DISPLAY 0.617021 (-1325 625);
PAINT GREEN (-1325 625);
FORCEPROP 1 LAST SCH_TITLE SMBUS: CPU PCIE HP
J 0
(-5300 550);
DISPLAY 1.212766 (-5300 550);
PAINT ORANGE (-5300 550);
FORCEPROP 1 LAST SCH_NUMBER H4694802
J 0
(1350 650);
DISPLAY 1.212766 (1350 650);
PAINT YELLOW (1350 650);
FORCEPROP 1 LAST SCH_DEPT BESD
J 1
(-1800 600);
DISPLAY 1.212766 (-1800 600);
PAINT YELLOW (-1800 600);
FORCEPROP 1 LAST SCH_REV 2.420
J 0
(2400 650);
DISPLAY 0.978723 (2400 650);
PAINT YELLOW (2400 650);
FORCEPROP 2 LAST CDS_LIB mstr_symbols
J 0
(2650 500);
PAINT MONO (2650 500);
DISPLAY INVISIBLE (2650 500);
FORCEPROP 2 LAST PAGE_BORDER TRUE
J 0
(-5240 5750);
DISPLAY 0.617021 (-5240 5750);
PAINT PINK (-5240 5750);
DISPLAY INVISIBLE (-5240 5750);
FORCEPROP 1 LAST COMMENT_BODY TRUE
J 0
(2662 512);
DISPLAY 0.468085 (2662 512);
PAINT GREEN (2662 512);
DISPLAY INVISIBLE (2662 512);
FORCEPROP 2 LAST CDS_XR_PAGE_TITLE CR-163 : @BASEBOARD_FAB2_LIB.BASEBOARD_FAB2(SCH_1):PAGE163
J 0
(-5240 5750);
DISPLAY 0.638298 (-5240 5750);
PAINT PINK (-5240 5750);
DISPLAY INVISIBLE (-5240 5750);
WIRE 16 -1 (-1950 3725)(-1950 3650);
WIRE 16 -1 (-1275 3650)(-1275 3725);
WIRE 16 -1 (-1200 3400)(-1100 3400);
WIRE 16 -1 (-1100 3400)(-1100 4000);
WIRE 16 -1 (-1100 4000)(-1200 4000);
WIRE 16 -1 (-1200 4000)(-1275 4000);
WIRE 16 -1 (-1200 4100)(-1200 4000);
WIRE 16 -1 (-1275 4000)(-1275 3925);
WIRE 16 -1 (-600 3750)(-600 3900);
WIRE 16 -1 (-600 3900)(-675 3900);
WIRE 16 -1 (-675 3900)(-750 3900);
WIRE 16 -1 (-675 3900)(-675 4000);
WIRE 16 -1 (-750 3900)(-750 3750);
WIRE 16 -1 (-2350 3750)(-2350 3875);
WIRE 16 -1 (-2350 3875)(-2400 3875);
WIRE 16 -1 (-2400 3875)(-2475 3875);
WIRE 16 -1 (-2400 3875)(-2400 3950);
WIRE 16 -1 (-2475 3750)(-2475 3875);
WIRE 16 -1 (-2000 3400)(-2100 3400);
WIRE 16 -1 (-2100 3400)(-2100 4000);
WIRE 16 -1 (-2100 4000)(-2025 4000);
WIRE 16 -1 (-2025 4000)(-1950 4000);
WIRE 16 -1 (-2025 4100)(-2025 4000);
WIRE 16 -1 (-1950 4000)(-1950 3925);
WIRE 16 682 (-3125 2825)(-3125 3525);
WIRE 16 682 (-4150 2825)(-3125 2825);
WIRE 16 682 (-3125 3525)(-4150 3525);
WIRE 16 682 (-4150 3525)(-4150 2825);
WIRE 16 -1 (-4775 3250)(-3525 3250);
FORCEPROP 2 LAST SIG_NAME SMB_CPU1_PE_HP_GTL_SDA
J 0
(-4750 3260);
DISPLAY 0.617021 (-4750 3260);
PAINT ORANGE (-4750 3260);
WIRE 16 -1 (-4050 3300)(-4775 3300);
FORCEPROP 2 LAST SIG_NAME SMB_CPU1_PE_HP_GTL_SCL
J 0
(-4750 3310);
DISPLAY 0.617021 (-4750 3310);
PAINT ORANGE (-4750 3310);
WIRE 16 -1 (-2475 3550)(-2475 3300);
WIRE 16 -1 (-2475 3300)(-2000 3300);
WIRE 16 -1 (-3850 3300)(-2475 3300);
FORCEPROP 2 LAST SIG_NAME SMB_CPU1_PE_HP_GTL_R_SCL
J 0
(-3050 3310);
DISPLAY 0.617021 (-3050 3310);
PAINT ORANGE (-3050 3310);
FORCEPROP 2 LASTPROP $XRERR UNIQUE?
J 0
(-3290 3310);
DISPLAY 0.638298 (-3290 3310);
PAINT MONO (-3290 3310);
DISPLAY INVISIBLE (-3290 3310);
WIRE 16 -1 (-2000 3250)(-2350 3250);
WIRE 16 -1 (-2350 3550)(-2350 3250);
WIRE 16 -1 (-2350 3250)(-3325 3250);
FORCEPROP 2 LAST SIG_NAME SMB_CPU1_PE_HP_GTL_R_SDA
J 0
(-3050 3260);
DISPLAY 0.617021 (-3050 3260);
PAINT ORANGE (-3050 3260);
FORCEPROP 2 LASTPROP $XRERR UNIQUE?
J 0
(-3290 3260);
DISPLAY 0.638298 (-3290 3260);
PAINT MONO (-3290 3260);
DISPLAY INVISIBLE (-3290 3260);
WIRE 16 -1 (-2000 3150)(-2675 3150);
FORCEPROP 2 LAST SIG_NAME TP_SMB_PEHPCPU1_EN
J 0
(-2675 3160);
DISPLAY 0.617021 (-2675 3160);
PAINT ORANGE (-2675 3160);
FORCEPROP 2 LASTPROP $XRERR UNIQUE?
J 0
(-2915 3150);
DISPLAY 0.638298 (-2915 3150);
PAINT MONO (-2915 3150);
DISPLAY INVISIBLE (-2915 3150);
WIRE 16 -1 (-750 3550)(-750 3300);
WIRE 16 -1 (-750 3300)(-300 3300);
WIRE 16 -1 (-850 3300)(-750 3300);
WIRE 16 -1 (-850 3300)(-850 2875);
WIRE 16 -1 (-1200 3300)(-850 3300);
FORCEPROP 0 LAST SIG_NAME SMB_PEHPCPU1_STBY_LVC3_R_SCL
J 0
(-1060 3310);
DISPLAY 0.617021 (-1060 3310);
PAINT ORANGE (-1060 3310);
FORCEPROP 2 LASTPROP $XRERR UNIQUE?
J 0
(-1300 3310);
DISPLAY 0.638298 (-1300 3310);
PAINT MONO (-1300 3310);
DISPLAY INVISIBLE (-1300 3310);
WIRE 16 -1 (-850 2875)(-250 2875);
WIRE 16 -1 (0 2825)(-950 2825);
WIRE 16 -1 (-950 3250)(-950 2825);
WIRE 16 -1 (-600 3250)(-950 3250);
WIRE 16 -1 (-950 3250)(-1200 3250);
FORCEPROP 0 LAST SIG_NAME SMB_PEHPCPU1_STBY_LVC3_R_SDA
J 0
(-1060 3260);
DISPLAY 0.617021 (-1060 3260);
PAINT ORANGE (-1060 3260);
FORCEPROP 2 LASTPROP $XRERR UNIQUE?
J 0
(-1300 3260);
DISPLAY 0.638298 (-1300 3260);
PAINT MONO (-1300 3260);
DISPLAY INVISIBLE (-1300 3260);
WIRE 16 -1 (-600 3250)(-50 3250);
WIRE 16 -1 (-600 3550)(-600 3250);
WIRE 16 -1 (-50 2875)(950 2875);
WIRE 16 -1 (-100 3300)(900 3300);
FORCEPROP 0 LAST SIG_NAME SMB_PEHPCPU1_STBY_LVC3_SCL
J 0
(215 3310);
DISPLAY 0.617021 (215 3310);
PAINT ORANGE (215 3310);
WIRE 16 -1 (950 2825)(200 2825);
FORCEPROP 0 LAST SIG_NAME SMB_SLOTX24_BMC_STBY_LVC3_SDA
J 2
(977 2836);
DISPLAY 0.617021 (977 2836);
PAINT ORANGE (977 2836);
WIRE 16 -1 (900 3250)(150 3250);
FORCEPROP 0 LAST SIG_NAME SMB_PEHPCPU1_STBY_LVC3_SDA
J 0
(215 3260);
DISPLAY 0.617021 (215 3260);
PAINT ORANGE (215 3260);
DOT 1 (-2475 3300);
DOT 1 (-2350 3250);
DOT 1 (-2025 4000);
DOT 1 (-1200 4000);
DOT 1 (-950 3250);
DOT 1 (-850 3300);
DOT 1 (-750 3300);
DOT 1 (-600 3250);
DOT 1 (-675 3900);
DOT 1 (-2400 3875);
FORCENOTE
ROOM=SMB_PE_HP_CPU1
(-5250 700) 0;
DISPLAY LEFT (-5250 700);
DISPLAY 1.021277 (-5250 700);
PAINT PURPLE (-5250 700);
FORCENOTE
THAN 3"  FROM CPU1
(-4125 2875) 0;
DISPLAY LEFT (-4125 2875);
DISPLAY 0.808511 (-4125 2875);
PAINT PURPLE (-4125 2875);
FORCENOTE
PLACE SEIRES RESISTORS NO MORE
(-4125 2950) 0;
DISPLAY LEFT (-4125 2950);
DISPLAY 0.808511 (-4125 2950);
PAINT PURPLE (-4125 2950);
FORCENOTE
PE HP SMBUS ADDRESS 0X22
(-1925 2550) 0;
DISPLAY LEFT (-1925 2550);
DISPLAY 1.021277 (-1925 2550);
PAINT PURPLE (-1925 2550);
FORCENOTE
PLACE CAPS & PU RESISTORS NEAR PCA9517
(-1875 4400) 0;
DISPLAY LEFT (-1875 4400);
DISPLAY 1.021277 (-1875 4400);
PAINT PURPLE (-1875 4400);
QUIT
